# S9S_MB_2U (Grand Teton) — schematic netlist excerpt (pin names and nets, part order shuffled) for the footprints in the layout excerpt that follows; sources: Cadence DE-HDL packaged netlist, KiCad conversion of 03242023_DA0F0TMBIJ0_F0T_Motherboard_J_brd_V01_OCP.brd

R3972  Q_RES  0 5% EMPTY  pkg 0402LF  page 192 : A = P12V_E1S_PWRGD_0 ; B = HP_LVC3_E1S_0_HSC_PWRGD
C969  Q_CAP  10UF 6.3V 20% X6S  pkg C0402  page 74 : A = PVCCIN_CPU0 ; B = GND

(kicad_pcb
	(version 20260206)
	(generator "pcbnew")
	(generator_version "10.0")
	(general
		(thickness 1.6)
		(legacy_teardrops no)
	)
	(paper "A4")
	(title_block
		(title "03242023_DA0F0TMBIJ0_F0T_Motherboard_J_brd_V01_OCP.brd")
		(comment 1 "Grand Teton / footprints 919-920 of 6105")
	)
	(layers
		(0 "F.Cu" signal "TOP")
		(4 "In1.Cu" signal "GND")
		(6 "In2.Cu" signal "IN1")
		(8 "In3.Cu" signal "GND1")
		(10 "In4.Cu" signal "IN2")
		(12 "In5.Cu" signal "GND2")
		(14 "In6.Cu" signal "IN3")
		(16 "In7.Cu" signal "GND3")
		(18 "In8.Cu" signal "VCC")
		(20 "In9.Cu" signal "VCC1")
		(22 "In10.Cu" signal "GND4")
		(24 "In11.Cu" signal "IN4")
		(26 "In12.Cu" signal "GND5")
		(28 "In13.Cu" signal "IN5")
		(30 "In14.Cu" signal "GND6")
		(32 "In15.Cu" signal "IN6")
		(34 "In16.Cu" signal "GND7")
		(2 "B.Cu" signal "BOTTOM")
		(9 "F.Adhes" user "F.Adhesive")
		(11 "B.Adhes" user "B.Adhesive")
		(13 "F.Paste" user "Package Geometry/Pastemask Top")
		(15 "B.Paste" user "Package Geometry/Pastemask Bottom")
		(5 "F.SilkS" user "Ref Des/Silkscreen Top")
		(7 "B.SilkS" user "Ref Des/Silkscreen Bottom")
		(1 "F.Mask" user "Board Geometry/Soldermask Top")
		(3 "B.Mask" user "Board Geometry/Soldermask Bottom")
		(17 "Dwgs.User" user "User.Drawings")
		(19 "Cmts.User" user "User.Comments")
		(21 "Eco1.User" user "User.Eco1")
		(23 "Eco2.User" user "User.Eco2")
		(25 "Edge.Cuts" user "Board Geometry/Outline")
		(27 "Margin" user)
		(31 "F.CrtYd" user "Package Geometry/Place Bound Top")
		(29 "B.CrtYd" user "Package Geometry/Place Bound Bottom")
		(35 "F.Fab" user "Ref Des/Assembly Top")
		(33 "B.Fab" user "Ref Des/Assembly Bottom")
	)
	(footprint ""
		(layer "F.Cu")
		(at 364.50143 -249.320304 -90)
		(property "Reference" "C969"
			(at 0 0 270)
			(layer "F.SilkS")
			(hide yes)
			(effects
				(font
					(size 1.27 1.27)
				)
			)
		)
		(property "Value" ""
			(at 0 0 270)
			(layer "F.Fab")
			(effects
				(font
					(size 1.27 1.27)
				)
			)
		)
		(duplicate_pad_numbers_are_jumpers no)
		(fp_line
			(start -0.7874 0.4064)
			(end -0.7874 -0.4064)
			(stroke
				(width 0.1524)
				(type default)
			)
			(layer "F.SilkS")
		)
		(fp_line
			(start 0.7874 0.4064)
			(end -0.7874 0.4064)
			(stroke
				(width 0.1524)
				(type default)
			)
			(layer "F.SilkS")
		)
		(fp_line
			(start -0.7874 -0.4064)
			(end 0.7874 -0.4064)
			(stroke
				(width 0.1524)
				(type default)
			)
			(layer "F.SilkS")
		)
		(fp_line
			(start 0.7874 -0.4064)
			(end 0.7874 0.4064)
			(stroke
				(width 0.1524)
				(type default)
			)
			(layer "F.SilkS")
		)
		(fp_line
			(start -0.67945 0.3048)
			(end -0.67945 -0.305054)
			(stroke
				(width 0.1)
				(type default)
			)
			(layer "F.Fab")
		)
		(fp_line
			(start -0.12065 0.3048)
			(end -0.67945 0.3048)
			(stroke
				(width 0.1)
				(type default)
			)
			(layer "F.Fab")
		)
		(fp_line
			(start 0.120396 0.3048)
			(end 0.120396 0.2794)
			(stroke
				(width 0.1)
				(type default)
			)
			(layer "F.Fab")
		)
		(fp_line
			(start 0.67945 0.3048)
			(end 0.120396 0.3048)
			(stroke
				(width 0.1)
				(type default)
			)
			(layer "F.Fab")
		)
		(fp_line
			(start -0.12065 0.2794)
			(end -0.12065 0.3048)
			(stroke
				(width 0.1)
				(type default)
			)
			(layer "F.Fab")
		)
		(fp_line
			(start 0.120396 0.2794)
			(end -0.12065 0.2794)
			(stroke
				(width 0.1)
				(type default)
			)
			(layer "F.Fab")
		)
		(fp_line
			(start -0.12065 -0.2794)
			(end 0.12065 -0.2794)
			(stroke
				(width 0.1)
				(type default)
			)
			(layer "F.Fab")
		)
		(fp_line
			(start 0.12065 -0.2794)
			(end 0.12065 -0.3048)
			(stroke
				(width 0.1)
				(type default)
			)
			(layer "F.Fab")
		)
		(fp_line
			(start 0.12065 -0.3048)
			(end 0.67945 -0.3048)
			(stroke
				(width 0.1)
				(type default)
			)
			(layer "F.Fab")
		)
		(fp_line
			(start 0.67945 -0.3048)
			(end 0.67945 0.3048)
			(stroke
				(width 0.1)
				(type default)
			)
			(layer "F.Fab")
		)
		(fp_line
			(start -0.67945 -0.305054)
			(end -0.12065 -0.305054)
			(stroke
				(width 0.1)
				(type default)
			)
			(layer "F.Fab")
		)
		(fp_line
			(start -0.12065 -0.305054)
			(end -0.12065 -0.2794)
			(stroke
				(width 0.1)
				(type default)
			)
			(layer "F.Fab")
		)
		(pad "1" smd circle
			(at -0.40005 0 270)
			(size 0 0)
			(layers "F.Cu" "F.Mask" "F.Paste")
			(net "PVCCIN_CPU0")
		)
		(pad "2" smd circle
			(at 0.40005 0 270)
			(size 0 0)
			(layers "F.Cu" "F.Mask" "F.Paste")
			(net "GND")
		)
	)
	(footprint ""
		(layer "F.Cu")
		(at 250.317 -38.048946 -90)
		(property "Reference" "R3972"
			(at 0 0 270)
			(layer "F.SilkS")
			(hide yes)
			(effects
				(font
					(size 1.27 1.27)
				)
			)
		)
		(property "Value" ""
			(at 0 0 270)
			(layer "F.Fab")
			(effects
				(font
					(size 1.27 1.27)
				)
			)
		)
		(duplicate_pad_numbers_are_jumpers no)
		(fp_line
			(start -0.7874 0.4064)
			(end -0.7874 -0.4064)
			(stroke
				(width 0.1524)
				(type default)
			)
			(layer "F.SilkS")
		)
		(fp_line
			(start 0.7874 0.4064)
			(end -0.7874 0.4064)
			(stroke
				(width 0.1524)
				(type default)
			)
			(layer "F.SilkS")
		)
		(fp_line
			(start -0.7874 -0.4064)
			(end 0.7874 -0.4064)
			(stroke
				(width 0.1524)
				(type default)
			)
			(layer "F.SilkS")
		)
		(fp_line
			(start 0.7874 -0.4064)
			(end 0.7874 0.4064)
			(stroke
				(width 0.1524)
				(type default)
			)
			(layer "F.SilkS")
		)
		(fp_line
			(start -0.67945 0.3048)
			(end -0.67945 -0.305054)
			(stroke
				(width 0.1)
				(type default)
			)
			(layer "F.Fab")
		)
		(fp_line
			(start -0.12065 0.3048)
			(end -0.67945 0.3048)
			(stroke
				(width 0.1)
				(type default)
			)
			(layer "F.Fab")
		)
		(fp_line
			(start 0.120396 0.3048)
			(end 0.120396 0.2794)
			(stroke
				(width 0.1)
				(type default)
			)
			(layer "F.Fab")
		)
		(fp_line
			(start 0.67945 0.3048)
			(end 0.120396 0.3048)
			(stroke
				(width 0.1)
				(type default)
			)
			(layer "F.Fab")
		)
		(fp_line
			(start -0.12065 0.2794)
			(end -0.12065 0.3048)
			(stroke
				(width 0.1)
				(type default)
			)
			(layer "F.Fab")
		)
		(fp_line
			(start 0.120396 0.2794)
			(end -0.12065 0.2794)
			(stroke
				(width 0.1)
				(type default)
			)
			(layer "F.Fab")
		)
		(fp_line
			(start -0.12065 -0.2794)
			(end 0.12065 -0.2794)
			(stroke
				(width 0.1)
				(type default)
			)
			(layer "F.Fab")
		)
		(fp_line
			(start 0.12065 -0.2794)
			(end 0.12065 -0.3048)
			(stroke
				(width 0.1)
				(type default)
			)
			(layer "F.Fab")
		)
		(fp_line
			(start 0.12065 -0.3048)
			(end 0.67945 -0.3048)
			(stroke
				(width 0.1)
				(type default)
			)
			(layer "F.Fab")
		)
		(fp_line
			(start 0.67945 -0.3048)
			(end 0.67945 0.3048)
			(stroke
				(width 0.1)
				(type default)
			)
			(layer "F.Fab")
		)
		(fp_line
			(start -0.67945 -0.305054)
			(end -0.12065 -0.305054)
			(stroke
				(width 0.1)
				(type default)
			)
			(layer "F.Fab")
		)
		(fp_line
			(start -0.12065 -0.305054)
			(end -0.12065 -0.2794)
			(stroke
				(width 0.1)
				(type default)
			)
			(layer "F.Fab")
		)
		(pad "1" smd circle
			(at -0.40005 0 270)
			(size 0 0)
			(layers "F.Cu" "F.Mask" "F.Paste")
			(net "P12V_E1S_PWRGD_0")
		)
		(pad "2" smd circle
			(at 0.40005 0 270)
			(size 0 0)
			(layers "F.Cu" "F.Mask" "F.Paste")
			(net "HP_LVC3_E1S_0_HSC_PWRGD")
		)
	)
)
